(kicad_pcb
	(version 20241229)
	(generator "pcbnew")
	(generator_version "9.0")
	(general
		(thickness 1.61)
		(legacy_teardrops no)
	)
	(paper "A3")
	(title_block
		(title "SO-DIMM DDR5 Tester")
		(date "2025-11-26")
		(rev "1.3.0")
		(comment 9 "footprint 59 of 627 (U4), pads 577-649 of 676")
	)
	(layers
		(0 "F.Cu" signal)
		(4 "In1.Cu" power)
		(6 "In2.Cu" mixed)
		(8 "In3.Cu" power)
		(10 "In4.Cu" mixed)
		(12 "In5.Cu" power)
		(14 "In6.Cu" mixed)
		(16 "In7.Cu" power)
		(18 "In8.Cu" power)
		(20 "In9.Cu" mixed)
		(22 "In10.Cu" power)
		(2 "B.Cu" signal)
		(9 "F.Adhes" user "F.Adhesive")
		(11 "B.Adhes" user "B.Adhesive")
		(13 "F.Paste" user)
		(15 "B.Paste" user)
		(5 "F.SilkS" user "F.Silkscreen")
		(7 "B.SilkS" user "B.Silkscreen")
		(1 "F.Mask" user)
		(3 "B.Mask" user)
		(17 "Dwgs.User" user "User.Drawings")
		(19 "Cmts.User" user "User.Comments")
		(21 "Eco1.User" user "User.Eco1")
		(23 "Eco2.User" user "User.Eco2")
		(25 "Edge.Cuts" user)
		(27 "Margin" user)
		(31 "F.CrtYd" user "F.Courtyard")
		(29 "B.CrtYd" user "B.Courtyard")
		(35 "F.Fab" user)
		(33 "B.Fab" user)
	)
	(footprint "antmicro-footprints:BGA-676_27x27mm_Layout26x26_P1x1mm_FFG676"
		(layer "F.Cu")
		(at 138.875501 174.801 180)
		(descr "FPGA XC7K160TFBG676")
		(tags "FPGA XC7K160TFBG676")
		(property "Reference" "U4"
			(at -12.224499 14.051 180)
			(layer "F.SilkS")
			(effects
				(font
					(size 0.7 0.7)
					(thickness 0.15)
				)
				(justify left bottom)
			)
		)
		(property "Value" "XC7K160T-FFG676"
			(at 0 15.5 180)
			(layer "F.Fab")
			(effects
				(font
					(size 0.7 0.7)
					(thickness 0.15)
				)
				(justify left bottom)
			)
		)
		(property "Datasheet" "https://docs.xilinx.com/v/u/en-US/ds180_7Series_Overview"
			(at 0 0 180)
			(layer "F.Fab")
			(hide yes)
			(effects
				(font
					(size 1.27 1.27)
					(thickness 0.15)
				)
			)
		)
		(property "Author" "Antmicro"
			(at 277.751002 349.602 0)
			(layer "F.Fab")
			(hide yes)
			(effects
				(font
					(size 1 1)
					(thickness 0.15)
				)
			)
		)
		(property "License" "Apache-2.0"
			(at 277.751002 349.602 0)
			(layer "F.Fab")
			(hide yes)
			(effects
				(font
					(size 1 1)
					(thickness 0.15)
				)
			)
		)
		(property "MPN" "XC7K160T-FFG676"
			(at 277.751002 349.602 0)
			(layer "F.Fab")
			(hide yes)
			(effects
				(font
					(size 1 1)
					(thickness 0.15)
				)
			)
		)
		(property "Manufacturer" "AMD-Xilinx"
			(at 277.751002 349.602 0)
			(layer "F.Fab")
			(hide yes)
			(effects
				(font
					(size 1 1)
					(thickness 0.15)
				)
			)
		)
		(sheetname "/FPGA Config/")
		(sheetfile "fpga-config.kicad_sch")
		(attr smd)
		(pad "U5" smd circle
			(at -8.5 3.499 180)
			(size 0.5 0.5)
			(layers "F.Cu" "F.Mask" "F.Paste")
			(net 287 "/DDR5 SODIMM/B.DQ29")
			(pinfunction "IO_L1N_T0_34")
			(pintype "bidirectional")
			(die_length 13.682)
		)
		(pad "U6" smd circle
			(at -7.5 3.499 180)
			(size 0.5 0.5)
			(layers "F.Cu" "F.Mask" "F.Paste")
			(net 286 "/DDR5 SODIMM/B.DQ28")
			(pinfunction "IO_L1P_T0_34")
			(pintype "bidirectional")
			(die_length 13.683)
		)
		(pad "U7" smd circle
			(at -6.5 3.499 180)
			(size 0.5 0.5)
			(layers "F.Cu" "F.Mask" "F.Paste")
			(net 289 "/DDR5 SODIMM/B.DQ31")
			(pinfunction "IO_L5P_T0_34")
			(pintype "bidirectional")
			(die_length 12.718)
		)
		(pad "U8" smd circle
			(at -5.5 3.499 180)
			(size 0.5 0.5)
			(layers "F.Cu" "F.Mask" "F.Paste")
			(net 1 "GND")
			(pinfunction "GND")
			(pintype "passive")
		)
		(pad "U9" smd circle
			(at -4.5 3.499 180)
			(size 0.5 0.5)
			(layers "F.Cu" "F.Mask" "F.Paste")
			(net 684 "/FPGA banks HP/VRN")
			(pinfunction "IO_0_VRN_33")
			(pintype "bidirectional")
			(die_length 7.601)
		)
		(pad "U10" smd circle
			(at -3.5 3.499 180)
			(size 0.5 0.5)
			(layers "F.Cu" "F.Mask" "F.Paste")
			(net 1 "GND")
			(pinfunction "GND")
			(pintype "passive")
		)
		(pad "U11" smd circle
			(at -2.5 3.499 180)
			(size 0.5 0.5)
			(layers "F.Cu" "F.Mask" "F.Paste")
			(net 188 "+1V8")
			(pinfunction "VCCAUX")
			(pintype "passive")
		)
		(pad "U12" smd circle
			(at -1.5 3.499 180)
			(size 0.5 0.5)
			(layers "F.Cu" "F.Mask" "F.Paste")
			(net 1 "GND")
			(pinfunction "GND")
			(pintype "passive")
		)
		(pad "U13" smd circle
			(at -0.5 3.499 180)
			(size 0.5 0.5)
			(layers "F.Cu" "F.Mask" "F.Paste")
			(net 227 "+1V0")
			(pinfunction "VCCBRAM")
			(pintype "passive")
		)
		(pad "U14" smd circle
			(at 0.499 3.499 180)
			(size 0.5 0.5)
			(layers "F.Cu" "F.Mask" "F.Paste")
			(net 1 "GND")
			(pinfunction "GND")
			(pintype "passive")
		)
		(pad "U15" smd circle
			(at 1.499 3.499 180)
			(size 0.5 0.5)
			(layers "F.Cu" "F.Mask" "F.Paste")
			(net 227 "+1V0")
			(pinfunction "VCCINT")
			(pintype "passive")
		)
		(pad "U16" smd circle
			(at 2.499 3.499 180)
			(size 0.5 0.5)
			(layers "F.Cu" "F.Mask" "F.Paste")
			(net 566 "unconnected-(U4B-IO_25_13-PadU16)")
			(pinfunction "IO_25_13")
			(pintype "bidirectional+no_connect")
			(die_length 9.654)
		)
		(pad "U17" smd circle
			(at 3.499 3.499 180)
			(size 0.5 0.5)
			(layers "F.Cu" "F.Mask" "F.Paste")
			(net 567 "unconnected-(U4B-IO_L23P_T3_13-PadU17)")
			(pinfunction "IO_L23P_T3_13")
			(pintype "bidirectional+no_connect")
			(die_length 11.04)
		)
		(pad "U18" smd circle
			(at 4.499 3.499 180)
			(size 0.5 0.5)
			(layers "F.Cu" "F.Mask" "F.Paste")
			(net 1 "GND")
			(pinfunction "GND")
			(pintype "passive")
		)
		(pad "U19" smd circle
			(at 5.499 3.499 180)
			(size 0.5 0.5)
			(layers "F.Cu" "F.Mask" "F.Paste")
			(net 568 "unconnected-(U4B-IO_L18P_T2_13-PadU19)")
			(pinfunction "IO_L18P_T2_13")
			(pintype "bidirectional+no_connect")
			(die_length 8.112)
		)
		(pad "U20" smd circle
			(at 6.499 3.499 180)
			(size 0.5 0.5)
			(layers "F.Cu" "F.Mask" "F.Paste")
			(net 569 "unconnected-(U4B-IO_L18N_T2_13-PadU20)")
			(pinfunction "IO_L18N_T2_13")
			(pintype "bidirectional+no_connect")
			(die_length 9.928)
		)
		(pad "U21" smd circle
			(at 7.499 3.499 180)
			(size 0.5 0.5)
			(layers "F.Cu" "F.Mask" "F.Paste")
			(net 570 "unconnected-(U4A-IO_0_12-PadU21)")
			(pinfunction "IO_0_12")
			(pintype "bidirectional+no_connect")
			(die_length 9.631)
		)
		(pad "U22" smd circle
			(at 8.499 3.499 180)
			(size 0.5 0.5)
			(layers "F.Cu" "F.Mask" "F.Paste")
			(net 573 "unconnected-(U4A-IO_L1P_T0_12-PadU22)")
			(pinfunction "IO_L1P_T0_12")
			(pintype "bidirectional+no_connect")
			(die_length 10.705)
		)
		(pad "U23" smd circle
			(at 9.499 3.499 180)
			(size 0.5 0.5)
			(layers "F.Cu" "F.Mask" "F.Paste")
			(net 200 "+3V3")
			(pinfunction "VCCO_12")
			(pintype "passive")
		)
		(pad "U24" smd circle
			(at 10.499 3.499 180)
			(size 0.5 0.5)
			(layers "F.Cu" "F.Mask" "F.Paste")
			(net 574 "unconnected-(U4A-IO_L2P_T0_12-PadU24)")
			(pinfunction "IO_L2P_T0_12")
			(pintype "bidirectional+no_connect")
			(die_length 12.37)
		)
		(pad "U25" smd circle
			(at 11.499 3.499 180)
			(size 0.5 0.5)
			(layers "F.Cu" "F.Mask" "F.Paste")
			(net 676 "/Ethernet/ETH.RXD3")
			(pinfunction "IO_L2N_T0_12")
			(pintype "bidirectional")
			(die_length 14.162)
		)
		(pad "U26" smd circle
			(at 12.499 3.499 180)
			(size 0.5 0.5)
			(layers "F.Cu" "F.Mask" "F.Paste")
			(net 732 "/Ethernet/ETH.TX_CTL")
			(pinfunction "IO_L4P_T0_12")
			(pintype "bidirectional")
			(die_length 15.43)
		)
		(pad "V1" smd circle
			(at -12.5 4.499 180)
			(size 0.5 0.5)
			(layers "F.Cu" "F.Mask" "F.Paste")
			(net 270 "/DDR5 SODIMM/B.DQ22")
			(pinfunction "IO_L8N_T1_34")
			(pintype "bidirectional")
			(die_length 17.73)
		)
		(pad "V2" smd circle
			(at -11.5 4.499 180)
			(size 0.5 0.5)
			(layers "F.Cu" "F.Mask" "F.Paste")
			(net 271 "/DDR5 SODIMM/B.DQ23")
			(pinfunction "IO_L8P_T1_34")
			(pintype "bidirectional")
			(die_length 16.717)
		)
		(pad "V3" smd circle
			(at -10.5 4.499 180)
			(size 0.5 0.5)
			(layers "F.Cu" "F.Mask" "F.Paste")
			(net 278 "/DDR5 SODIMM/B.DQ27")
			(pinfunction "IO_L4P_T0_34")
			(pintype "bidirectional")
			(die_length 16.996)
		)
		(pad "V4" smd circle
			(at -9.5 4.499 180)
			(size 0.5 0.5)
			(layers "F.Cu" "F.Mask" "F.Paste")
			(net 277 "/DDR5 SODIMM/B.DQ26")
			(pinfunction "IO_L6P_T0_34")
			(pintype "bidirectional")
			(die_length 16.475)
		)
		(pad "V5" smd circle
			(at -8.5 4.499 180)
			(size 0.5 0.5)
			(layers "F.Cu" "F.Mask" "F.Paste")
			(net 1 "GND")
			(pinfunction "GND")
			(pintype "passive")
		)
		(pad "V6" smd circle
			(at -7.5 4.499 180)
			(size 0.5 0.5)
			(layers "F.Cu" "F.Mask" "F.Paste")
			(net 288 "/DDR5 SODIMM/B.DQ30")
			(pinfunction "IO_L5N_T0_34")
			(pintype "bidirectional")
			(die_length 13.667)
		)
		(pad "V7" smd circle
			(at -6.5 4.499 180)
			(size 0.5 0.5)
			(layers "F.Cu" "F.Mask" "F.Paste")
			(net 183 "/DDR5 SODIMM/B.CA0")
			(pinfunction "IO_L2N_T0_33")
			(pintype "bidirectional")
			(die_length 12.123)
		)
		(pad "V8" smd circle
			(at -5.5 4.499 180)
			(size 0.5 0.5)
			(layers "F.Cu" "F.Mask" "F.Paste")
			(net 179 "/DDR5 SODIMM/B.CA2")
			(pinfunction "IO_L2P_T0_33")
			(pintype "bidirectional")
			(die_length 11.194)
		)
		(pad "V9" smd circle
			(at -4.5 4.499 180)
			(size 0.5 0.5)
			(layers "F.Cu" "F.Mask" "F.Paste")
			(net 178 "/DDR5 SODIMM/B.CA3")
			(pinfunction "IO_L6P_T0_33")
			(pintype "bidirectional")
			(die_length 10.483)
		)
		(pad "V10" smd circle
			(at -3.5 4.499 180)
			(size 0.5 0.5)
			(layers "F.Cu" "F.Mask" "F.Paste")
			(net 206 "+1V1")
			(pinfunction "VCCO_33")
			(pintype "passive")
		)
		(pad "V11" smd circle
			(at -2.5 4.499 180)
			(size 0.5 0.5)
			(layers "F.Cu" "F.Mask" "F.Paste")
			(net 167 "/DDR5 SODIMM/B.CA10")
			(pinfunction "IO_L1P_T0_33")
			(pintype "bidirectional")
			(die_length 9.051)
		)
		(pad "V12" smd circle
			(at -1.5 4.499 180)
			(size 0.5 0.5)
			(layers "F.Cu" "F.Mask" "F.Paste")
			(net 685 "/FPGA banks HP/VRP")
			(pinfunction "IO_25_VRP_33")
			(pintype "bidirectional")
			(die_length 8.364)
		)
		(pad "V13" smd circle
			(at -0.5 4.499 180)
			(size 0.5 0.5)
			(layers "F.Cu" "F.Mask" "F.Paste")
			(net 119 "/DDR5 SODIMM/A.CB3")
			(pinfunction "IO_0_VRN_32")
			(pintype "bidirectional")
			(die_length 8.061)
		)
		(pad "V14" smd circle
			(at 0.499 4.499 180)
			(size 0.5 0.5)
			(layers "F.Cu" "F.Mask" "F.Paste")
			(net 55 "/DDR5 SODIMM/A.DQ0")
			(pinfunction "IO_L24P_T3_32")
			(pintype "bidirectional")
			(die_length 12.558)
		)
		(pad "V15" smd circle
			(at 1.499 4.499 180)
			(size 0.5 0.5)
			(layers "F.Cu" "F.Mask" "F.Paste")
			(net 1 "GND")
			(pinfunction "GND")
			(pintype "passive")
		)
		(pad "V16" smd circle
			(at 2.499 4.499 180)
			(size 0.5 0.5)
			(layers "F.Cu" "F.Mask" "F.Paste")
			(net 57 "/DDR5 SODIMM/A.DQ1")
			(pinfunction "IO_L20P_T3_32")
			(pintype "bidirectional")
			(die_length 18.47)
		)
		(pad "V17" smd circle
			(at 3.499 4.499 180)
			(size 0.5 0.5)
			(layers "F.Cu" "F.Mask" "F.Paste")
			(net 59 "/DDR5 SODIMM/A.DQ2")
			(pinfunction "IO_L20N_T3_32")
			(pintype "bidirectional")
			(die_length 18.818)
		)
		(pad "V18" smd circle
			(at 4.499 4.499 180)
			(size 0.5 0.5)
			(layers "F.Cu" "F.Mask" "F.Paste")
			(net 61 "/DDR5 SODIMM/A.DQ3")
			(pinfunction "IO_L23P_T3_32")
			(pintype "bidirectional")
			(die_length 17.507)
		)
		(pad "V19" smd circle
			(at 5.499 4.499 180)
			(size 0.5 0.5)
			(layers "F.Cu" "F.Mask" "F.Paste")
			(net 65 "/DDR5 SODIMM/A.~{DM0}")
			(pinfunction "IO_L23N_T3_32")
			(pintype "bidirectional")
			(die_length 18.005)
		)
		(pad "V20" smd circle
			(at 6.499 4.499 180)
			(size 0.5 0.5)
			(layers "F.Cu" "F.Mask" "F.Paste")
			(net 200 "+3V3")
			(pinfunction "VCCO_12")
			(pintype "passive")
		)
		(pad "V21" smd circle
			(at 7.499 4.499 180)
			(size 0.5 0.5)
			(layers "F.Cu" "F.Mask" "F.Paste")
			(net 575 "unconnected-(U4A-IO_L6P_T0_12-PadV21)")
			(pinfunction "IO_L6P_T0_12")
			(pintype "bidirectional+no_connect")
			(die_length 8.805)
		)
		(pad "V22" smd circle
			(at 8.499 4.499 180)
			(size 0.5 0.5)
			(layers "F.Cu" "F.Mask" "F.Paste")
			(net 576 "unconnected-(U4A-IO_L1N_T0_12-PadV22)")
			(pinfunction "IO_L1N_T0_12")
			(pintype "bidirectional+no_connect")
			(die_length 10.787)
		)
		(pad "V23" smd circle
			(at 9.499 4.499 180)
			(size 0.5 0.5)
			(layers "F.Cu" "F.Mask" "F.Paste")
			(net 577 "unconnected-(U4A-IO_L3P_T0_DQS_12-PadV23)")
			(pinfunction "IO_L3P_T0_DQS_12")
			(pintype "bidirectional+no_connect")
			(die_length 12.224)
		)
		(pad "V24" smd circle
			(at 10.499 4.499 180)
			(size 0.5 0.5)
			(layers "F.Cu" "F.Mask" "F.Paste")
			(net 578 "unconnected-(U4A-IO_L3N_T0_DQS_12-PadV24)")
			(pinfunction "IO_L3N_T0_DQS_12")
			(pintype "bidirectional+no_connect")
			(die_length 12.691)
		)
		(pad "V25" smd circle
			(at 11.499 4.499 180)
			(size 0.5 0.5)
			(layers "F.Cu" "F.Mask" "F.Paste")
			(net 1 "GND")
			(pinfunction "GND")
			(pintype "passive")
		)
		(pad "V26" smd circle
			(at 12.499 4.499 180)
			(size 0.5 0.5)
			(layers "F.Cu" "F.Mask" "F.Paste")
			(net 675 "/Ethernet/ETH.RXD2")
			(pinfunction "IO_L4N_T0_12")
			(pintype "bidirectional")
			(die_length 15.219)
		)
		(pad "W1" smd circle
			(at -12.5 5.499 180)
			(size 0.5 0.5)
			(layers "F.Cu" "F.Mask" "F.Paste")
			(net 268 "/DDR5 SODIMM/B.DQ20")
			(pinfunction "IO_L10P_T1_34")
			(pintype "bidirectional")
			(die_length 18.423)
		)
		(pad "W2" smd circle
			(at -11.5 5.499 180)
			(size 0.5 0.5)
			(layers "F.Cu" "F.Mask" "F.Paste")
			(net 1 "GND")
			(pinfunction "GND")
			(pintype "passive")
		)
		(pad "W3" smd circle
			(at -10.5 5.499 180)
			(size 0.5 0.5)
			(layers "F.Cu" "F.Mask" "F.Paste")
			(net 276 "/DDR5 SODIMM/B.DQ25")
			(pinfunction "IO_L4N_T0_34")
			(pintype "bidirectional")
			(die_length 18.698)
		)
		(pad "W4" smd circle
			(at -9.5 5.499 180)
			(size 0.5 0.5)
			(layers "F.Cu" "F.Mask" "F.Paste")
			(net 10 "/FPGA banks HP/VREF")
			(pinfunction "IO_L6N_T0_VREF_34")
			(pintype "bidirectional")
			(die_length 18.8)
		)
		(pad "W5" smd circle
			(at -8.5 5.499 180)
			(size 0.5 0.5)
			(layers "F.Cu" "F.Mask" "F.Paste")
			(net 279 "/DDR5 SODIMM/B.DQS3_N")
			(pinfunction "IO_L3N_T0_DQS_34")
			(pintype "bidirectional")
			(die_length 17.539)
		)
		(pad "W6" smd circle
			(at -7.5 5.499 180)
			(size 0.5 0.5)
			(layers "F.Cu" "F.Mask" "F.Paste")
			(net 283 "/DDR5 SODIMM/B.DQS3_P")
			(pinfunction "IO_L3P_T0_DQS_34")
			(pintype "bidirectional")
			(die_length 17.741)
		)
		(pad "W7" smd circle
			(at -6.5 5.499 180)
			(size 0.5 0.5)
			(layers "F.Cu" "F.Mask" "F.Paste")
			(net 206 "+1V1")
			(pinfunction "VCCO_33")
			(pintype "passive")
		)
		(pad "W8" smd circle
			(at -5.5 5.499 180)
			(size 0.5 0.5)
			(layers "F.Cu" "F.Mask" "F.Paste")
			(net 10 "/FPGA banks HP/VREF")
			(pinfunction "IO_L6N_T0_VREF_33")
			(pintype "bidirectional")
			(die_length 12.359)
		)
		(pad "W9" smd circle
			(at -4.5 5.499 180)
			(size 0.5 0.5)
			(layers "F.Cu" "F.Mask" "F.Paste")
			(net 174 "/DDR5 SODIMM/B.CA6")
			(pinfunction "IO_L3N_T0_DQS_33")
			(pintype "bidirectional")
			(die_length 12.347)
		)
		(pad "W10" smd circle
			(at -3.5 5.499 180)
			(size 0.5 0.5)
			(layers "F.Cu" "F.Mask" "F.Paste")
			(net 166 "/DDR5 SODIMM/B.CA11")
			(pinfunction "IO_L3P_T0_DQS_33")
			(pintype "bidirectional")
			(die_length 12.577)
		)
		(pad "W11" smd circle
			(at -2.5 5.499 180)
			(size 0.5 0.5)
			(layers "F.Cu" "F.Mask" "F.Paste")
			(net 165 "/DDR5 SODIMM/B.CA12")
			(pinfunction "IO_L1N_T0_33")
			(pintype "bidirectional")
			(die_length 9.991)
		)
		(pad "W12" smd circle
			(at -1.5 5.499 180)
			(size 0.5 0.5)
			(layers "F.Cu" "F.Mask" "F.Paste")
			(net 1 "GND")
			(pinfunction "GND")
			(pintype "passive")
		)
		(pad "W13" smd circle
			(at -0.5 5.499 180)
			(size 0.5 0.5)
			(layers "F.Cu" "F.Mask" "F.Paste")
			(net 116 "/DDR5 SODIMM/A.CB2")
			(pinfunction "IO_25_VRP_32")
			(pintype "bidirectional")
			(die_length 8.841)
		)
		(pad "W14" smd circle
			(at 0.499 5.499 180)
			(size 0.5 0.5)
			(layers "F.Cu" "F.Mask" "F.Paste")
			(net 73 "/DDR5 SODIMM/A.DQ7")
			(pinfunction "IO_L24N_T3_32")
			(pintype "bidirectional")
			(die_length 12.441)
		)
		(pad "W15" smd circle
			(at 1.499 5.499 180)
			(size 0.5 0.5)
			(layers "F.Cu" "F.Mask" "F.Paste")
			(net 70 "/DDR5 SODIMM/A.DQ4")
			(pinfunction "IO_L22P_T3_32")
			(pintype "bidirectional")
			(die_length 13.547)
		)
		(pad "W16" smd circle
			(at 2.499 5.499 180)
			(size 0.5 0.5)
			(layers "F.Cu" "F.Mask" "F.Paste")
			(net 71 "/DDR5 SODIMM/A.DQ5")
			(pinfunction "IO_L22N_T3_32")
			(pintype "bidirectional")
			(die_length 15.068)
		)
		(pad "W17" smd circle
			(at 3.499 5.499 180)
			(size 0.5 0.5)
			(layers "F.Cu" "F.Mask" "F.Paste")
			(net 206 "+1V1")
			(pinfunction "VCCO_32")
			(pintype "passive")
		)
		(pad "W18" smd circle
			(at 4.499 5.499 180)
			(size 0.5 0.5)
			(layers "F.Cu" "F.Mask" "F.Paste")
			(net 69 "/DDR5 SODIMM/A.DQS0_P")
			(pinfunction "IO_L21P_T3_DQS_32")
			(pintype "bidirectional")
			(die_length 16.431)
		)
		(pad "W19" smd circle
			(at 5.499 5.499 180)
			(size 0.5 0.5)
			(layers "F.Cu" "F.Mask" "F.Paste")
			(net 68 "/DDR5 SODIMM/A.DQS0_N")
			(pinfunction "IO_L21N_T3_DQS_32")
			(pintype "bidirectional")
			(die_length 16.437)
		)
		(pad "W20" smd circle
			(at 6.499 5.499 180)
			(size 0.5 0.5)
			(layers "F.Cu" "F.Mask" "F.Paste")
			(net 579 "unconnected-(U4A-IO_L15P_T2_DQS_12-PadW20)")
			(pinfunction "IO_L15P_T2_DQS_12")
			(pintype "bidirectional+no_connect")
			(die_length 9.921)
		)
		(pad "W21" smd circle
			(at 7.499 5.499 180)
			(size 0.5 0.5)
			(layers "F.Cu" "F.Mask" "F.Paste")
			(net 580 "unconnected-(U4A-IO_L6N_T0_VREF_12-PadW21)")
			(pinfunction "IO_L6N_T0_VREF_12")
			(pintype "bidirectional+no_connect")
			(die_length 9.947)
		)
		(pad "W22" smd circle
			(at 8.499 5.499 180)
			(size 0.5 0.5)
			(layers "F.Cu" "F.Mask" "F.Paste")
			(net 1 "GND")
			(pinfunction "GND")
			(pintype "passive")
		)
		(pad "W23" smd circle
			(at 9.499 5.499 180)
			(size 0.5 0.5)
			(layers "F.Cu" "F.Mask" "F.Paste")
			(net 581 "unconnected-(U4A-IO_L8P_T1_12-PadW23)")
			(pinfunction "IO_L8P_T1_12")
			(pintype "bidirectional+no_connect")
			(die_length 12.009)
		)
		(pad "W24" smd circle
			(at 10.499 5.499 180)
			(size 0.5 0.5)
			(layers "F.Cu" "F.Mask" "F.Paste")
			(net 733 "/Ethernet/ETH.TXD0")
			(pinfunction "IO_L8N_T1_12")
			(pintype "bidirectional")
			(die_length 13.111)
		)
		(pad "W25" smd circle
			(at 11.499 5.499 180)
			(size 0.5 0.5)
			(layers "F.Cu" "F.Mask" "F.Paste")
			(net 674 "/Ethernet/ETH.RXD1")
			(pinfunction "IO_L5P_T0_12")
			(pintype "bidirectional")
			(die_length 14.107)
		)
	)
)
